(kicad_pcb
	(version 20260206)
	(generator "pcbnew")
	(generator_version "10.0")
	(general
		(thickness 0.77098)
		(legacy_teardrops no)
	)
	(paper "A4")
	(title_block
		(title "gnss-m2-zed-f9t — M2_ZED-F9T_MODULE.PcbDoc")
		(comment 1 "Time Appliance Project (Time Card) / footprints 1-7 of 36")
	)
	(layers
		(0 "F.Cu" signal "L01-Top Layer")
		(4 "In1.Cu" signal "L02-Inner Layer")
		(6 "In2.Cu" signal "L03-Inner Layer")
		(2 "B.Cu" signal "L04-Bottom Layer")
		(9 "F.Adhes" user "F.Adhesive")
		(11 "B.Adhes" user "B.Adhesive")
		(13 "F.Paste" user "Top Paste")
		(15 "B.Paste" user "Bottom Paste")
		(5 "F.SilkS" user "Top Overlay")
		(7 "B.SilkS" user "Bottom Overlay")
		(1 "F.Mask" user "Top Solder")
		(3 "B.Mask" user "Bottom Solder")
		(17 "Dwgs.User" user "User.Drawings")
		(19 "Cmts.User" user "User.Comments")
		(21 "Eco1.User" user "User.Eco1")
		(23 "Eco2.User" user "User.Eco2")
		(25 "Edge.Cuts" user)
		(27 "Margin" user)
		(31 "F.CrtYd" user "Top Courtyard")
		(29 "B.CrtYd" user "Bottom Courtyard")
		(35 "F.Fab" user "Top Component Outline")
		(33 "B.Fab" user "Bottom Component Outline 2")
	)
	(footprint "Vault:FP-0402-L_1_0_0_05-W_0_5-IPC_B"
		(layer "F.Cu")
		(at 141.501105 91.0036 -90)
		(property "Reference" "C11"
			(at -2.29999 5.307371 270)
			(unlocked yes)
			(layer "F.SilkS")
			(effects
				(font
					(face "Arial")
					(size 0.96012 0.96012)
					(thickness 0.254)
				)
			)
		)
		(property "Value" "100nF"
			(at 2.70399 2.099971 270)
			(unlocked yes)
			(layer "F.SilkS")
			(hide yes)
			(effects
				(font
					(face "Arial")
					(size 0.96012 0.96012)
					(thickness 0.254)
				)
			)
		)
		(sheetname "02-Antenna_Supervisor")
		(sheetfile "02-Antenna_Supervisor.kicad_sch")
		(duplicate_pad_numbers_are_jumpers no)
		(fp_line
			(start -0.88624 0.43624)
			(end -0.88624 -0.43624)
			(stroke
				(width 0.2)
				(type solid)
			)
			(layer "F.CrtYd")
		)
		(fp_line
			(start 0.88624 0.43624)
			(end -0.88624 0.43624)
			(stroke
				(width 0.2)
				(type solid)
			)
			(layer "F.CrtYd")
		)
		(fp_line
			(start 0.88624 0.43624)
			(end 0.88624 -0.43624)
			(stroke
				(width 0.2)
				(type solid)
			)
			(layer "F.CrtYd")
		)
		(fp_line
			(start 0.88624 -0.43624)
			(end -0.88624 -0.43624)
			(stroke
				(width 0.2)
				(type solid)
			)
			(layer "F.CrtYd")
		)
		(fp_line
			(start 0 0.5)
			(end 0 -0.5)
			(stroke
				(width 0.1)
				(type solid)
			)
			(layer "F.Fab")
		)
		(fp_line
			(start -0.88624 0.43624)
			(end -0.88624 -0.43624)
			(stroke
				(width 0.2)
				(type solid)
			)
			(layer "F.Fab")
		)
		(fp_line
			(start 0.88624 0.43624)
			(end -0.88624 0.43624)
			(stroke
				(width 0.2)
				(type solid)
			)
			(layer "F.Fab")
		)
		(fp_line
			(start 0.88624 0.43624)
			(end 0.88624 -0.43624)
			(stroke
				(width 0.2)
				(type solid)
			)
			(layer "F.Fab")
		)
		(fp_line
			(start 0.5 0)
			(end -0.5 0)
			(stroke
				(width 0.1)
				(type solid)
			)
			(layer "F.Fab")
		)
		(fp_line
			(start 0.88624 -0.43624)
			(end -0.88624 -0.43624)
			(stroke
				(width 0.2)
				(type solid)
			)
			(layer "F.Fab")
		)
		(fp_text user "${REFERENCE}"
			(at -0.00001 0.09602 270)
			(unlocked yes)
			(layer "F.Fab")
			(effects
				(font
					(face "Arial")
					(size 0.63 0.63)
					(thickness 0.1)
				)
				(justify left bottom)
			)
		)
		(pad "1" smd rect
			(at -0.42856 0 270)
			(size 0.61535 0.57247)
			(layers "F.Cu" "F.Mask" "F.Paste")
			(net "+3V3")
			(solder_mask_margin 0)
			(solder_paste_margin 0)
		)
		(pad "2" smd rect
			(at 0.42856 0 270)
			(size 0.61535 0.57247)
			(layers "F.Cu" "F.Mask" "F.Paste")
			(net "GND")
			(solder_mask_margin 0)
			(solder_paste_margin 0)
		)
	)
	(footprint "Vault:FP-RMCF0402-MFG"
		(layer "F.Cu")
		(at 153.501105 116.3036)
		(property "Reference" "R4"
			(at -1.3 -0.180485 0)
			(unlocked yes)
			(layer "F.SilkS")
			(effects
				(font
					(face "Arial")
					(size 0.40005 0.40005)
					(thickness 0.1778)
				)
			)
		)
		(property "Value" "1k"
			(at -5.114945 5.014445 270)
			(unlocked yes)
			(layer "F.SilkS")
			(hide yes)
			(effects
				(font
					(face "Arial")
					(size 0.40005 0.40005)
					(thickness 0.1778)
				)
			)
		)
		(sheetname "01-M2_ZED-F9T_MODULE")
		(sheetfile "01-M2_ZED-F9T_MODULE.kicad_sch")
		(duplicate_pad_numbers_are_jumpers no)
		(fp_line
			(start -0.55 -0.7)
			(end 0.55 -0.7)
			(stroke
				(width 0.2)
				(type solid)
			)
			(layer "F.SilkS")
		)
		(fp_line
			(start -0.55 0.7)
			(end 0.55 0.7)
			(stroke
				(width 0.2)
				(type solid)
			)
			(layer "F.SilkS")
		)
		(fp_line
			(start -0.85 -0.4)
			(end 0.85 -0.4)
			(stroke
				(width 0.2)
				(type solid)
			)
			(layer "F.CrtYd")
		)
		(fp_line
			(start -0.85 0.4)
			(end -0.85 -0.4)
			(stroke
				(width 0.2)
				(type solid)
			)
			(layer "F.CrtYd")
		)
		(fp_line
			(start -0.85 0.4)
			(end 0.85 0.4)
			(stroke
				(width 0.2)
				(type solid)
			)
			(layer "F.CrtYd")
		)
		(fp_line
			(start 0.85 0.4)
			(end 0.85 -0.4)
			(stroke
				(width 0.2)
				(type solid)
			)
			(layer "F.CrtYd")
		)
		(fp_line
			(start -0.85 -0.4)
			(end 0.85 -0.4)
			(stroke
				(width 0.2)
				(type solid)
			)
			(layer "F.Fab")
		)
		(fp_line
			(start -0.85 0.4)
			(end -0.85 -0.4)
			(stroke
				(width 0.2)
				(type solid)
			)
			(layer "F.Fab")
		)
		(fp_line
			(start -0.85 0.4)
			(end 0.85 0.4)
			(stroke
				(width 0.2)
				(type solid)
			)
			(layer "F.Fab")
		)
		(fp_line
			(start -0.5 0)
			(end 0.5 0)
			(stroke
				(width 0.1)
				(type solid)
			)
			(layer "F.Fab")
		)
		(fp_line
			(start 0 0.5)
			(end 0 -0.5)
			(stroke
				(width 0.1)
				(type solid)
			)
			(layer "F.Fab")
		)
		(fp_line
			(start 0.85 0.4)
			(end 0.85 -0.4)
			(stroke
				(width 0.2)
				(type solid)
			)
			(layer "F.Fab")
		)
		(fp_text user "${REFERENCE}"
			(at -0.00001 0.10711 360)
			(unlocked yes)
			(layer "F.Fab")
			(effects
				(font
					(face "Arial")
					(size 0.63 0.63)
					(thickness 0.1)
				)
				(justify left bottom)
			)
		)
		(pad "1" smd rect
			(at -0.5 0)
			(size 0.5 0.6)
			(layers "F.Cu" "F.Mask" "F.Paste")
			(net "GND")
			(solder_mask_margin 0)
			(solder_paste_margin 0)
		)
		(pad "2" smd rect
			(at 0.5 0)
			(size 0.5 0.6)
			(layers "F.Cu" "F.Mask" "F.Paste")
			(net "NetD2_1")
			(solder_mask_margin 0)
			(solder_paste_margin 0)
		)
	)
	(footprint "Vault:FP-GRM31C-0_2-e0_3_0_8-IPC_C"
		(layer "F.Cu")
		(at 140.001105 119.2036 180)
		(property "Reference" "C7"
			(at -0.5 1.596754 0)
			(unlocked yes)
			(layer "F.SilkS")
			(effects
				(font
					(face "Arial")
					(size 0.48006 0.48006)
					(thickness 0.254)
				)
			)
		)
		(property "Value" "47uF_6.3V_1206"
			(at 8.366015 2.430251 180)
			(unlocked yes)
			(layer "F.SilkS")
			(hide yes)
			(effects
				(font
					(face "Arial")
					(size 0.96012 0.96012)
					(thickness 0.254)
				)
			)
		)
		(sheetname "03-M2_GoldFingers")
		(sheetfile "03-M2_GoldFingers.kicad_sch")
		(duplicate_pad_numbers_are_jumpers no)
		(fp_line
			(start 0.39847 0.9)
			(end -0.39846 0.9)
			(stroke
				(width 0.2)
				(type solid)
			)
			(layer "F.SilkS")
		)
		(fp_line
			(start 0.39847 -0.9)
			(end -0.39846 -0.9)
			(stroke
				(width 0.2)
				(type solid)
			)
			(layer "F.SilkS")
		)
		(fp_line
			(start 1.9531 1)
			(end -1.9531 1)
			(stroke
				(width 0.2)
				(type solid)
			)
			(layer "F.CrtYd")
		)
		(fp_line
			(start 1.9531 -1)
			(end 1.9531 1)
			(stroke
				(width 0.2)
				(type solid)
			)
			(layer "F.CrtYd")
		)
		(fp_line
			(start 1.9531 -1)
			(end -1.9531 -1)
			(stroke
				(width 0.2)
				(type solid)
			)
			(layer "F.CrtYd")
		)
		(fp_line
			(start -1.9531 -1)
			(end -1.9531 1)
			(stroke
				(width 0.2)
				(type solid)
			)
			(layer "F.CrtYd")
		)
		(fp_line
			(start 1.9531 1)
			(end -1.9531 1)
			(stroke
				(width 0.2)
				(type solid)
			)
			(layer "F.Fab")
		)
		(fp_line
			(start 1.9531 -1)
			(end 1.9531 1)
			(stroke
				(width 0.2)
				(type solid)
			)
			(layer "F.Fab")
		)
		(fp_line
			(start 1.9531 -1)
			(end -1.9531 -1)
			(stroke
				(width 0.2)
				(type solid)
			)
			(layer "F.Fab")
		)
		(fp_line
			(start 0.5 0)
			(end -0.5 0)
			(stroke
				(width 0.1)
				(type solid)
			)
			(layer "F.Fab")
		)
		(fp_line
			(start 0 -0.5)
			(end 0 0.5)
			(stroke
				(width 0.1)
				(type solid)
			)
			(layer "F.Fab")
		)
		(fp_line
			(start -1.9531 -1)
			(end -1.9531 1)
			(stroke
				(width 0.2)
				(type solid)
			)
			(layer "F.Fab")
		)
		(fp_text user "${REFERENCE}"
			(at -0.00001 0.09602 180)
			(unlocked yes)
			(layer "F.Fab")
			(effects
				(font
					(face "Arial")
					(size 0.63 0.63)
					(thickness 0.1)
				)
				(justify left bottom)
			)
		)
		(pad "1" smd rect
			(at -1.27578 0 180)
			(size 1.15464 1.7062)
			(layers "F.Cu" "F.Mask" "F.Paste")
			(net "+3V3")
			(solder_mask_margin 0)
			(solder_paste_margin 0)
		)
		(pad "2" smd rect
			(at 1.27578 0 180)
			(size 1.15464 1.7062)
			(layers "F.Cu" "F.Mask" "F.Paste")
			(net "GND")
			(solder_mask_margin 0)
			(solder_paste_margin 0)
		)
	)
	(footprint "Vault:HRS-U.FL-R-SMT-3_V"
		(layer "F.Cu")
		(at 154.631465 85.54119)
		(property "Reference" "P1"
			(at 3.260159 0.06241 270)
			(unlocked yes)
			(layer "F.SilkS")
			(effects
				(font
					(face "Arial")
					(size 0.96012 0.96012)
					(thickness 0.254)
				)
			)
		)
		(property "Value" "U.FL-R-SMT-1(01)"
			(at 8.619685 3.367981 0)
			(unlocked yes)
			(layer "F.SilkS")
			(hide yes)
			(effects
				(font
					(face "Arial")
					(size 0.96012 0.96012)
					(thickness 0.254)
				)
			)
		)
		(sheetname "02-Antenna_Supervisor")
		(sheetfile "02-Antenna_Supervisor.kicad_sch")
		(duplicate_pad_numbers_are_jumpers no)
		(fp_line
			(start -0.55 -1.3)
			(end 0.55 -1.3)
			(stroke
				(width 0.2)
				(type solid)
			)
			(layer "F.SilkS")
		)
		(fp_circle
			(center -2.55 0)
			(end -2.55 -0.125)
			(stroke
				(width 0.25)
				(type solid)
			)
			(fill no)
			(layer "F.SilkS")
		)
		(fp_line
			(start -2.1 -1.4)
			(end 2.1 -1.4)
			(stroke
				(width 0.05)
				(type solid)
			)
			(layer "F.CrtYd")
		)
		(fp_line
			(start -2.1 2.15)
			(end -2.1 -1.4)
			(stroke
				(width 0.05)
				(type solid)
			)
			(layer "F.CrtYd")
		)
		(fp_line
			(start -2.1 2.15)
			(end 2.1 2.15)
			(stroke
				(width 0.05)
				(type solid)
			)
			(layer "F.CrtYd")
		)
		(fp_line
			(start -0.5 0)
			(end 0.5 0)
			(stroke
				(width 0.1)
				(type solid)
			)
			(layer "F.CrtYd")
		)
		(fp_line
			(start 0 0.5)
			(end 0 -0.5)
			(stroke
				(width 0.1)
				(type solid)
			)
			(layer "F.CrtYd")
		)
		(fp_line
			(start 2.1 2.15)
			(end 2.1 -1.4)
			(stroke
				(width 0.05)
				(type solid)
			)
			(layer "F.CrtYd")
		)
		(pad "1" smd rect
			(at -1.475 0 180)
			(size 1.05 2.2)
			(layers "F.Cu" "F.Mask" "F.Paste")
			(net "GND")
		)
		(pad "2" smd rect
			(at 1.475 0 180)
			(size 1.05 2.2)
			(layers "F.Cu" "F.Mask" "F.Paste")
			(net "GND")
		)
		(pad "3" smd rect
			(at 0 1.525 180)
			(size 1 1.05)
			(layers "F.Cu" "F.Mask" "F.Paste")
			(net "RF_ANT")
		)
	)
	(footprint "Vault:FP-GRM033-0_03-IPC_B"
		(layer "F.Cu")
		(at 152.697275 89.90197 -90)
		(property "Reference" "C12"
			(at 2.104835 -0.381387 270)
			(unlocked yes)
			(layer "F.SilkS")
			(effects
				(font
					(size 0.635 0.635)
					(thickness 0.2032)
				)
			)
		)
		(property "Value" "10nF"
			(at -2.099971 2.24704 180)
			(unlocked yes)
			(layer "F.SilkS")
			(hide yes)
			(effects
				(font
					(face "Arial")
					(size 0.96012 0.96012)
					(thickness 0.254)
				)
			)
		)
		(sheetname "02-Antenna_Supervisor")
		(sheetfile "02-Antenna_Supervisor.kicad_sch")
		(duplicate_pad_numbers_are_jumpers no)
		(fp_line
			(start -0.68137 0.33137)
			(end -0.68137 -0.33137)
			(stroke
				(width 0.2)
				(type solid)
			)
			(layer "F.CrtYd")
		)
		(fp_line
			(start 0.68136 0.33137)
			(end -0.68137 0.33137)
			(stroke
				(width 0.2)
				(type solid)
			)
			(layer "F.CrtYd")
		)
		(fp_line
			(start 0.68136 0.33137)
			(end 0.68136 -0.33137)
			(stroke
				(width 0.2)
				(type solid)
			)
			(layer "F.CrtYd")
		)
		(fp_line
			(start 0.68136 -0.33137)
			(end -0.68137 -0.33137)
			(stroke
				(width 0.2)
				(type solid)
			)
			(layer "F.CrtYd")
		)
		(fp_line
			(start 0 0.5)
			(end 0 -0.5)
			(stroke
				(width 0.1)
				(type solid)
			)
			(layer "F.Fab")
		)
		(fp_line
			(start -0.68137 0.33137)
			(end -0.68137 -0.33137)
			(stroke
				(width 0.2)
				(type solid)
			)
			(layer "F.Fab")
		)
		(fp_line
			(start 0.68136 0.33137)
			(end -0.68137 0.33137)
			(stroke
				(width 0.2)
				(type solid)
			)
			(layer "F.Fab")
		)
		(fp_line
			(start 0.68136 0.33137)
			(end 0.68136 -0.33137)
			(stroke
				(width 0.2)
				(type solid)
			)
			(layer "F.Fab")
		)
		(fp_line
			(start 0.49999 0)
			(end -0.5 0)
			(stroke
				(width 0.1)
				(type solid)
			)
			(layer "F.Fab")
		)
		(fp_line
			(start 0.68136 -0.33137)
			(end -0.68137 -0.33137)
			(stroke
				(width 0.2)
				(type solid)
			)
			(layer "F.Fab")
		)
		(fp_text user "${REFERENCE}"
			(at -0.00001 0.09602 270)
			(unlocked yes)
			(layer "F.Fab")
			(effects
				(font
					(face "Arial")
					(size 0.63 0.63)
					(thickness 0.1)
				)
				(justify left bottom)
			)
		)
		(pad "1" smd rect
			(at -0.30431 0 270)
			(size 0.45411 0.36274)
			(layers "F.Cu" "F.Mask" "F.Paste")
			(net "NetC12_1")
			(solder_mask_margin 0)
			(solder_paste_margin 0)
		)
		(pad "2" smd rect
			(at 0.30431 0 270)
			(size 0.45411 0.36274)
			(layers "F.Cu" "F.Mask" "F.Paste")
			(net "GND")
			(solder_mask_margin 0)
			(solder_paste_margin 0)
		)
	)
	(footprint "Vault:FP-CL542-IPC_C"
		(layer "F.Cu")
		(at 146.303365 110.481 180)
		(property "Reference" "C1"
			(at 0.102255 -1.142115 0)
			(unlocked yes)
			(layer "F.SilkS")
			(effects
				(font
					(face "Arial")
					(size 0.40005 0.40005)
					(thickness 0.1778)
				)
			)
		)
		(property "Value" "1uF_25V_0402"
			(at 4.1259 1.959815 180)
			(unlocked yes)
			(layer "F.SilkS")
			(hide yes)
			(effects
				(font
					(face "Arial")
					(size 0.40005 0.40005)
					(thickness 0.1778)
				)
			)
		)
		(sheetname "01-M2_ZED-F9T_MODULE")
		(sheetfile "01-M2_ZED-F9T_MODULE.kicad_sch")
		(duplicate_pad_numbers_are_jumpers no)
		(fp_line
			(start 0.63624 0.67499)
			(end -0.63623 0.67499)
			(stroke
				(width 0.2)
				(type solid)
			)
			(layer "F.SilkS")
		)
		(fp_line
			(start 0.63624 -0.675)
			(end -0.63623 -0.675)
			(stroke
				(width 0.2)
				(type solid)
			)
			(layer "F.SilkS")
		)
		(fp_line
			(start 0.73624 0.375)
			(end -0.73623 0.375)
			(stroke
				(width 0.2)
				(type solid)
			)
			(layer "F.CrtYd")
		)
		(fp_line
			(start 0.73624 -0.37501)
			(end 0.73624 0.375)
			(stroke
				(width 0.2)
				(type solid)
			)
			(layer "F.CrtYd")
		)
		(fp_line
			(start 0.73624 -0.37501)
			(end -0.73623 -0.37501)
			(stroke
				(width 0.2)
				(type solid)
			)
			(layer "F.CrtYd")
		)
		(fp_line
			(start -0.73623 -0.37501)
			(end -0.73623 0.375)
			(stroke
				(width 0.2)
				(type solid)
			)
			(layer "F.CrtYd")
		)
		(fp_line
			(start 0.73624 0.375)
			(end -0.73623 0.375)
			(stroke
				(width 0.2)
				(type solid)
			)
			(layer "F.Fab")
		)
		(fp_line
			(start 0.73624 -0.37501)
			(end 0.73624 0.375)
			(stroke
				(width 0.2)
				(type solid)
			)
			(layer "F.Fab")
		)
		(fp_line
			(start 0.73624 -0.37501)
			(end -0.73623 -0.37501)
			(stroke
				(width 0.2)
				(type solid)
			)
			(layer "F.Fab")
		)
		(fp_line
			(start 0.5 0)
			(end -0.5 0)
			(stroke
				(width 0.1)
				(type solid)
			)
			(layer "F.Fab")
		)
		(fp_line
			(start 0.5 0)
			(end -0.5 0)
			(stroke
				(width 0.1)
				(type solid)
			)
			(layer "F.Fab")
		)
		(fp_line
			(start 0 -0.5)
			(end 0 0.49999)
			(stroke
				(width 0.1)
				(type solid)
			)
			(layer "F.Fab")
		)
		(fp_line
			(start 0 -0.5)
			(end 0 0.49999)
			(stroke
				(width 0.1)
				(type solid)
			)
			(layer "F.Fab")
		)
		(fp_line
			(start -0.73623 -0.37501)
			(end -0.73623 0.375)
			(stroke
				(width 0.2)
				(type solid)
			)
			(layer "F.Fab")
		)
		(fp_text user "${REFERENCE}"
			(at 0 0.28424 180)
			(unlocked yes)
			(layer "F.Fab")
			(effects
				(font
					(face "Arial")
					(size 0.63 0.63)
					(thickness 0.1)
				)
				(justify left bottom)
			)
		)
		(pad "1" smd rect
			(at -0.37856 0 180)
			(size 0.51535 0.47247)
			(layers "F.Cu" "F.Mask" "F.Paste")
			(net "+3V3")
			(solder_mask_margin 0)
			(solder_paste_margin 0)
		)
		(pad "2" smd rect
			(at 0.37857 0 180)
			(size 0.51535 0.47247)
			(layers "F.Cu" "F.Mask" "F.Paste")
			(net "GND")
			(solder_mask_margin 0)
			(solder_paste_margin 0)
		)
	)
	(footprint "Vault:FP-CRCW1218-HPe3-MFG"
		(layer "F.Cu")
		(at 149.501105 89.8036 -90)
		(property "Reference" "R16"
			(at -2.699924 -1.5 0)
			(unlocked yes)
			(layer "F.SilkS")
			(effects
				(font
					(face "Arial")
					(size 0.48006 0.48006)
					(thickness 0.254)
				)
			)
		)
		(property "Value" "22_1%_1218 1.5W"
			(at -2.385841 7.01935 180)
			(unlocked yes)
			(layer "F.SilkS")
			(hide yes)
			(effects
				(font
					(face "Arial")
					(size 0.96012 0.96012)
					(thickness 0.254)
				)
			)
		)
		(sheetname "02-Antenna_Supervisor")
		(sheetfile "02-Antenna_Supervisor.kicad_sch")
		(duplicate_pad_numbers_are_jumpers no)
		(fp_line
			(start 0.475 2.4)
			(end -0.475 2.4)
			(stroke
				(width 0.2)
				(type solid)
			)
			(layer "F.SilkS")
		)
		(fp_line
			(start 0.475 -2.4)
			(end -0.475 -2.4)
			(stroke
				(width 0.2)
				(type solid)
			)
			(layer "F.SilkS")
		)
		(fp_line
			(start -2.05 2.55)
			(end -2.05 -2.55)
			(stroke
				(width 0.2)
				(type solid)
			)
			(layer "F.CrtYd")
		)
		(fp_line
			(start 2.05 2.55)
			(end -2.05 2.55)
			(stroke
				(width 0.2)
				(type solid)
			)
			(layer "F.CrtYd")
		)
		(fp_line
			(start 2.05 2.55)
			(end 2.05 -2.55)
			(stroke
				(width 0.2)
				(type solid)
			)
			(layer "F.CrtYd")
		)
		(fp_line
			(start 2.05 -2.55)
			(end -2.05 -2.55)
			(stroke
				(width 0.2)
				(type solid)
			)
			(layer "F.CrtYd")
		)
		(fp_line
			(start -2.05 2.55)
			(end -2.05 -2.55)
			(stroke
				(width 0.2)
				(type solid)
			)
			(layer "F.Fab")
		)
		(fp_line
			(start 2.05 2.55)
			(end -2.05 2.55)
			(stroke
				(width 0.2)
				(type solid)
			)
			(layer "F.Fab")
		)
		(fp_line
			(start 2.05 2.55)
			(end 2.05 -2.55)
			(stroke
				(width 0.2)
				(type solid)
			)
			(layer "F.Fab")
		)
		(fp_line
			(start 0 0.5)
			(end 0 -0.5)
			(stroke
				(width 0.1)
				(type solid)
			)
			(layer "F.Fab")
		)
		(fp_line
			(start 0.5 0)
			(end -0.5 0)
			(stroke
				(width 0.1)
				(type solid)
			)
			(layer "F.Fab")
		)
		(fp_line
			(start 2.05 -2.55)
			(end -2.05 -2.55)
			(stroke
				(width 0.2)
				(type solid)
			)
			(layer "F.Fab")
		)
		(fp_text user "${REFERENCE}"
			(at -0.00001 0.09602 270)
			(unlocked yes)
			(layer "F.Fab")
			(effects
				(font
					(face "Arial")
					(size 0.63 0.63)
					(thickness 0.1)
				)
				(justify left bottom)
			)
		)
		(pad "1" smd rect
			(at -1.4 0 270)
			(size 1.1 4.9)
			(layers "F.Cu" "F.Mask" "F.Paste")
			(net "NetC12_1")
			(solder_mask_margin 0)
			(solder_paste_margin 0)
		)
		(pad "2" smd rect
			(at 1.4 0 270)
			(size 1.1 4.9)
			(layers "F.Cu" "F.Mask" "F.Paste")
			(net "NetQ1_3")
			(solder_mask_margin 0)
			(solder_paste_margin 0)
		)
	)
)
